(kicad_pcb
	(version 20260206)
	(generator "pcbnew")
	(generator_version "10.0")
	(general
		(thickness 1.6)
		(legacy_teardrops no)
	)
	(paper "A4")
	(title_block
		(title "01162023_DA0F0TEBIF0_F0T_Expander_BD_F_brd_V02_OCP.brd")
		(comment 1 "Grand Teton / footprints 2637-2643 of 9728")
	)
	(layers
		(0 "F.Cu" signal "TOP")
		(4 "In1.Cu" signal "GND")
		(6 "In2.Cu" signal "VCC")
		(8 "In3.Cu" signal "VCC1")
		(10 "In4.Cu" signal "GND1")
		(12 "In5.Cu" signal "IN1")
		(14 "In6.Cu" signal "GND2")
		(16 "In7.Cu" signal "IN2")
		(18 "In8.Cu" signal "GND3")
		(20 "In9.Cu" signal "IN3")
		(22 "In10.Cu" signal "GND4")
		(24 "In11.Cu" signal "IN4")
		(26 "In12.Cu" signal "GND5")
		(28 "In13.Cu" signal "IN5")
		(30 "In14.Cu" signal "GND6")
		(32 "In15.Cu" signal "IN6")
		(34 "In16.Cu" signal "GND7")
		(2 "B.Cu" signal "BOTTOM")
		(9 "F.Adhes" user "F.Adhesive")
		(11 "B.Adhes" user "B.Adhesive")
		(13 "F.Paste" user "Package Geometry/Pastemask Top")
		(15 "B.Paste" user "Package Geometry/Pastemask Bottom")
		(5 "F.SilkS" user "Ref Des/Silkscreen Top")
		(7 "B.SilkS" user "Ref Des/Silkscreen Bottom")
		(1 "F.Mask" user "Board Geometry/Soldermask Top")
		(3 "B.Mask" user "Board Geometry/Soldermask Bottom")
		(17 "Dwgs.User" user "User.Drawings")
		(19 "Cmts.User" user "User.Comments")
		(21 "Eco1.User" user "User.Eco1")
		(23 "Eco2.User" user "User.Eco2")
		(25 "Edge.Cuts" user "Board Geometry/Outline")
		(27 "Margin" user)
		(31 "F.CrtYd" user "Package Geometry/Place Bound Top")
		(29 "B.CrtYd" user "Package Geometry/Place Bound Bottom")
		(35 "F.Fab" user "Ref Des/Assembly Top")
		(33 "B.Fab" user "Ref Des/Assembly Bottom")
	)
	(footprint ""
		(layer "F.Cu")
		(at 142.343886 -42.84091)
		(property "Reference" "R549"
			(at 0 0 0)
			(layer "F.SilkS")
			(hide yes)
			(effects
				(font
					(size 1.27 1.27)
				)
			)
		)
		(property "Value" ""
			(at 0 0 0)
			(layer "F.Fab")
			(effects
				(font
					(size 1.27 1.27)
				)
			)
		)
		(duplicate_pad_numbers_are_jumpers no)
		(fp_line
			(start -0.7874 -0.4064)
			(end 0.7874 -0.4064)
			(stroke
				(width 0.1524)
				(type default)
			)
			(layer "F.SilkS")
		)
		(fp_line
			(start -0.7874 0.4064)
			(end -0.7874 -0.4064)
			(stroke
				(width 0.1524)
				(type default)
			)
			(layer "F.SilkS")
		)
		(fp_line
			(start 0.7874 -0.4064)
			(end 0.7874 0.4064)
			(stroke
				(width 0.1524)
				(type default)
			)
			(layer "F.SilkS")
		)
		(fp_line
			(start 0.7874 0.4064)
			(end -0.7874 0.4064)
			(stroke
				(width 0.1524)
				(type default)
			)
			(layer "F.SilkS")
		)
		(fp_line
			(start -0.67945 -0.305054)
			(end -0.12065 -0.305054)
			(stroke
				(width 0.1)
				(type default)
			)
			(layer "F.Fab")
		)
		(fp_line
			(start -0.67945 0.3048)
			(end -0.67945 -0.305054)
			(stroke
				(width 0.1)
				(type default)
			)
			(layer "F.Fab")
		)
		(fp_line
			(start -0.12065 -0.305054)
			(end -0.12065 -0.2794)
			(stroke
				(width 0.1)
				(type default)
			)
			(layer "F.Fab")
		)
		(fp_line
			(start -0.12065 -0.2794)
			(end 0.12065 -0.2794)
			(stroke
				(width 0.1)
				(type default)
			)
			(layer "F.Fab")
		)
		(fp_line
			(start -0.12065 0.2794)
			(end -0.12065 0.3048)
			(stroke
				(width 0.1)
				(type default)
			)
			(layer "F.Fab")
		)
		(fp_line
			(start -0.12065 0.3048)
			(end -0.67945 0.3048)
			(stroke
				(width 0.1)
				(type default)
			)
			(layer "F.Fab")
		)
		(fp_line
			(start 0.120396 0.2794)
			(end -0.12065 0.2794)
			(stroke
				(width 0.1)
				(type default)
			)
			(layer "F.Fab")
		)
		(fp_line
			(start 0.120396 0.3048)
			(end 0.120396 0.2794)
			(stroke
				(width 0.1)
				(type default)
			)
			(layer "F.Fab")
		)
		(fp_line
			(start 0.12065 -0.3048)
			(end 0.67945 -0.3048)
			(stroke
				(width 0.1)
				(type default)
			)
			(layer "F.Fab")
		)
		(fp_line
			(start 0.12065 -0.2794)
			(end 0.12065 -0.3048)
			(stroke
				(width 0.1)
				(type default)
			)
			(layer "F.Fab")
		)
		(fp_line
			(start 0.67945 -0.3048)
			(end 0.67945 0.3048)
			(stroke
				(width 0.1)
				(type default)
			)
			(layer "F.Fab")
		)
		(fp_line
			(start 0.67945 0.3048)
			(end 0.120396 0.3048)
			(stroke
				(width 0.1)
				(type default)
			)
			(layer "F.Fab")
		)
		(pad "1" smd circle
			(at -0.40005 0)
			(size 0 0)
			(layers "F.Cu" "F.Mask" "F.Paste")
			(net "SSD4_ADC_A1")
		)
		(pad "2" smd circle
			(at 0.40005 0)
			(size 0 0)
			(layers "F.Cu" "F.Mask" "F.Paste")
			(net "P3V3_AUX")
		)
	)
	(footprint ""
		(layer "F.Cu")
		(at 72.674988 -56.977534 180)
		(property "Reference" "PC376"
			(at 0 0 180)
			(layer "F.SilkS")
			(hide yes)
			(effects
				(font
					(size 1.27 1.27)
				)
			)
		)
		(property "Value" ""
			(at 0 0 180)
			(layer "F.Fab")
			(effects
				(font
					(size 1.27 1.27)
				)
			)
		)
		(duplicate_pad_numbers_are_jumpers no)
		(fp_line
			(start 0.7874 0.4064)
			(end -0.7874 0.4064)
			(stroke
				(width 0.1524)
				(type default)
			)
			(layer "F.SilkS")
		)
		(fp_line
			(start 0.7874 -0.4064)
			(end 0.7874 0.4064)
			(stroke
				(width 0.1524)
				(type default)
			)
			(layer "F.SilkS")
		)
		(fp_line
			(start -0.7874 0.4064)
			(end -0.7874 -0.4064)
			(stroke
				(width 0.1524)
				(type default)
			)
			(layer "F.SilkS")
		)
		(fp_line
			(start -0.7874 -0.4064)
			(end 0.7874 -0.4064)
			(stroke
				(width 0.1524)
				(type default)
			)
			(layer "F.SilkS")
		)
		(fp_line
			(start 0.67945 0.3048)
			(end 0.120396 0.3048)
			(stroke
				(width 0.1)
				(type default)
			)
			(layer "F.Fab")
		)
		(fp_line
			(start 0.67945 -0.3048)
			(end 0.67945 0.3048)
			(stroke
				(width 0.1)
				(type default)
			)
			(layer "F.Fab")
		)
		(fp_line
			(start 0.12065 -0.2794)
			(end 0.12065 -0.3048)
			(stroke
				(width 0.1)
				(type default)
			)
			(layer "F.Fab")
		)
		(fp_line
			(start 0.12065 -0.3048)
			(end 0.67945 -0.3048)
			(stroke
				(width 0.1)
				(type default)
			)
			(layer "F.Fab")
		)
		(fp_line
			(start 0.120396 0.3048)
			(end 0.120396 0.2794)
			(stroke
				(width 0.1)
				(type default)
			)
			(layer "F.Fab")
		)
		(fp_line
			(start 0.120396 0.2794)
			(end -0.12065 0.2794)
			(stroke
				(width 0.1)
				(type default)
			)
			(layer "F.Fab")
		)
		(fp_line
			(start -0.12065 0.3048)
			(end -0.67945 0.3048)
			(stroke
				(width 0.1)
				(type default)
			)
			(layer "F.Fab")
		)
		(fp_line
			(start -0.12065 0.2794)
			(end -0.12065 0.3048)
			(stroke
				(width 0.1)
				(type default)
			)
			(layer "F.Fab")
		)
		(fp_line
			(start -0.12065 -0.2794)
			(end 0.12065 -0.2794)
			(stroke
				(width 0.1)
				(type default)
			)
			(layer "F.Fab")
		)
		(fp_line
			(start -0.12065 -0.305054)
			(end -0.12065 -0.2794)
			(stroke
				(width 0.1)
				(type default)
			)
			(layer "F.Fab")
		)
		(fp_line
			(start -0.67945 0.3048)
			(end -0.67945 -0.305054)
			(stroke
				(width 0.1)
				(type default)
			)
			(layer "F.Fab")
		)
		(fp_line
			(start -0.67945 -0.305054)
			(end -0.12065 -0.305054)
			(stroke
				(width 0.1)
				(type default)
			)
			(layer "F.Fab")
		)
		(pad "1" smd circle
			(at -0.40005 0 180)
			(size 0 0)
			(layers "F.Cu" "F.Mask" "F.Paste")
			(net "P12V_AUX")
		)
		(pad "2" smd circle
			(at 0.40005 0 180)
			(size 0 0)
			(layers "F.Cu" "F.Mask" "F.Paste")
			(net "GND")
		)
	)
	(footprint ""
		(layer "F.Cu")
		(at 257.264408 -29.079952 180)
		(property "Reference" "R6206"
			(at 0 0 180)
			(layer "F.SilkS")
			(hide yes)
			(effects
				(font
					(size 1.27 1.27)
				)
			)
		)
		(property "Value" ""
			(at 0 0 180)
			(layer "F.Fab")
			(effects
				(font
					(size 1.27 1.27)
				)
			)
		)
		(duplicate_pad_numbers_are_jumpers no)
		(fp_line
			(start 0.7874 0.4064)
			(end -0.7874 0.4064)
			(stroke
				(width 0.1524)
				(type default)
			)
			(layer "F.SilkS")
		)
		(fp_line
			(start 0.7874 -0.4064)
			(end 0.7874 0.4064)
			(stroke
				(width 0.1524)
				(type default)
			)
			(layer "F.SilkS")
		)
		(fp_line
			(start -0.7874 0.4064)
			(end -0.7874 -0.4064)
			(stroke
				(width 0.1524)
				(type default)
			)
			(layer "F.SilkS")
		)
		(fp_line
			(start -0.7874 -0.4064)
			(end 0.7874 -0.4064)
			(stroke
				(width 0.1524)
				(type default)
			)
			(layer "F.SilkS")
		)
		(fp_line
			(start 0.67945 0.3048)
			(end 0.120396 0.3048)
			(stroke
				(width 0.1)
				(type default)
			)
			(layer "F.Fab")
		)
		(fp_line
			(start 0.67945 -0.3048)
			(end 0.67945 0.3048)
			(stroke
				(width 0.1)
				(type default)
			)
			(layer "F.Fab")
		)
		(fp_line
			(start 0.12065 -0.2794)
			(end 0.12065 -0.3048)
			(stroke
				(width 0.1)
				(type default)
			)
			(layer "F.Fab")
		)
		(fp_line
			(start 0.12065 -0.3048)
			(end 0.67945 -0.3048)
			(stroke
				(width 0.1)
				(type default)
			)
			(layer "F.Fab")
		)
		(fp_line
			(start 0.120396 0.3048)
			(end 0.120396 0.2794)
			(stroke
				(width 0.1)
				(type default)
			)
			(layer "F.Fab")
		)
		(fp_line
			(start 0.120396 0.2794)
			(end -0.12065 0.2794)
			(stroke
				(width 0.1)
				(type default)
			)
			(layer "F.Fab")
		)
		(fp_line
			(start -0.12065 0.3048)
			(end -0.67945 0.3048)
			(stroke
				(width 0.1)
				(type default)
			)
			(layer "F.Fab")
		)
		(fp_line
			(start -0.12065 0.2794)
			(end -0.12065 0.3048)
			(stroke
				(width 0.1)
				(type default)
			)
			(layer "F.Fab")
		)
		(fp_line
			(start -0.12065 -0.2794)
			(end 0.12065 -0.2794)
			(stroke
				(width 0.1)
				(type default)
			)
			(layer "F.Fab")
		)
		(fp_line
			(start -0.12065 -0.305054)
			(end -0.12065 -0.2794)
			(stroke
				(width 0.1)
				(type default)
			)
			(layer "F.Fab")
		)
		(fp_line
			(start -0.67945 0.3048)
			(end -0.67945 -0.305054)
			(stroke
				(width 0.1)
				(type default)
			)
			(layer "F.Fab")
		)
		(fp_line
			(start -0.67945 -0.305054)
			(end -0.12065 -0.305054)
			(stroke
				(width 0.1)
				(type default)
			)
			(layer "F.Fab")
		)
		(pad "1" smd circle
			(at -0.40005 0 180)
			(size 0 0)
			(layers "F.Cu" "F.Mask" "F.Paste")
			(net "GND")
		)
		(pad "2" smd circle
			(at 0.40005 0 180)
			(size 0 0)
			(layers "F.Cu" "F.Mask" "F.Paste")
			(net "SSD8_PWRDIS_R")
		)
	)
	(footprint ""
		(layer "F.Cu")
		(at 384.51282 -343.952322 90)
		(property "Reference" "C773"
			(at 0 0 90)
			(layer "F.SilkS")
			(hide yes)
			(effects
				(font
					(size 1.27 1.27)
				)
			)
		)
		(property "Value" ""
			(at 0 0 90)
			(layer "F.Fab")
			(effects
				(font
					(size 1.27 1.27)
				)
			)
		)
		(duplicate_pad_numbers_are_jumpers no)
		(fp_line
			(start 0.299974 -0.150114)
			(end 0.299974 0.150114)
			(stroke
				(width 0.1)
				(type default)
			)
			(layer "F.Fab")
		)
		(fp_line
			(start -0.299974 -0.150114)
			(end 0.299974 -0.150114)
			(stroke
				(width 0.1)
				(type default)
			)
			(layer "F.Fab")
		)
		(fp_line
			(start 0.299974 0.150114)
			(end -0.299974 0.150114)
			(stroke
				(width 0.1)
				(type default)
			)
			(layer "F.Fab")
		)
		(fp_line
			(start -0.299974 0.150114)
			(end -0.299974 -0.150114)
			(stroke
				(width 0.1)
				(type default)
			)
			(layer "F.Fab")
		)
		(pad "1" smd rect
			(at -0.2667 0 90)
			(size 0.3048 0.381)
			(layers "F.Cu" "F.Mask" "F.Paste")
			(net "P5E_PEX3_STN6_TX_DN<106>")
		)
		(pad "2" smd rect
			(at 0.2667 0 90)
			(size 0.3048 0.381)
			(layers "F.Cu" "F.Mask" "F.Paste")
			(net "P5E_PEX3_STN6_TX_C_DN<106>")
		)
	)
	(footprint ""
		(layer "F.Cu")
		(at 338.074 -159.766 180)
		(property "Reference" "R4812"
			(at 0 0 180)
			(layer "F.SilkS")
			(hide yes)
			(effects
				(font
					(size 1.27 1.27)
				)
			)
		)
		(property "Value" ""
			(at 0 0 180)
			(layer "F.Fab")
			(effects
				(font
					(size 1.27 1.27)
				)
			)
		)
		(duplicate_pad_numbers_are_jumpers no)
		(fp_line
			(start 0.7874 0.4064)
			(end -0.7874 0.4064)
			(stroke
				(width 0.1524)
				(type default)
			)
			(layer "F.SilkS")
		)
		(fp_line
			(start 0.7874 -0.4064)
			(end 0.7874 0.4064)
			(stroke
				(width 0.1524)
				(type default)
			)
			(layer "F.SilkS")
		)
		(fp_line
			(start -0.7874 0.4064)
			(end -0.7874 -0.4064)
			(stroke
				(width 0.1524)
				(type default)
			)
			(layer "F.SilkS")
		)
		(fp_line
			(start -0.7874 -0.4064)
			(end 0.7874 -0.4064)
			(stroke
				(width 0.1524)
				(type default)
			)
			(layer "F.SilkS")
		)
		(fp_line
			(start 0.67945 0.3048)
			(end 0.120396 0.3048)
			(stroke
				(width 0.1)
				(type default)
			)
			(layer "F.Fab")
		)
		(fp_line
			(start 0.67945 -0.3048)
			(end 0.67945 0.3048)
			(stroke
				(width 0.1)
				(type default)
			)
			(layer "F.Fab")
		)
		(fp_line
			(start 0.12065 -0.2794)
			(end 0.12065 -0.3048)
			(stroke
				(width 0.1)
				(type default)
			)
			(layer "F.Fab")
		)
		(fp_line
			(start 0.12065 -0.3048)
			(end 0.67945 -0.3048)
			(stroke
				(width 0.1)
				(type default)
			)
			(layer "F.Fab")
		)
		(fp_line
			(start 0.120396 0.3048)
			(end 0.120396 0.2794)
			(stroke
				(width 0.1)
				(type default)
			)
			(layer "F.Fab")
		)
		(fp_line
			(start 0.120396 0.2794)
			(end -0.12065 0.2794)
			(stroke
				(width 0.1)
				(type default)
			)
			(layer "F.Fab")
		)
		(fp_line
			(start -0.12065 0.3048)
			(end -0.67945 0.3048)
			(stroke
				(width 0.1)
				(type default)
			)
			(layer "F.Fab")
		)
		(fp_line
			(start -0.12065 0.2794)
			(end -0.12065 0.3048)
			(stroke
				(width 0.1)
				(type default)
			)
			(layer "F.Fab")
		)
		(fp_line
			(start -0.12065 -0.2794)
			(end 0.12065 -0.2794)
			(stroke
				(width 0.1)
				(type default)
			)
			(layer "F.Fab")
		)
		(fp_line
			(start -0.12065 -0.305054)
			(end -0.12065 -0.2794)
			(stroke
				(width 0.1)
				(type default)
			)
			(layer "F.Fab")
		)
		(fp_line
			(start -0.67945 0.3048)
			(end -0.67945 -0.305054)
			(stroke
				(width 0.1)
				(type default)
			)
			(layer "F.Fab")
		)
		(fp_line
			(start -0.67945 -0.305054)
			(end -0.12065 -0.305054)
			(stroke
				(width 0.1)
				(type default)
			)
			(layer "F.Fab")
		)
		(pad "1" smd circle
			(at -0.40005 0 180)
			(size 0 0)
			(layers "F.Cu" "F.Mask" "F.Paste")
			(net "PRSNT_SSD12_FPGA_PCA9555_N")
		)
		(pad "2" smd circle
			(at 0.40005 0 180)
			(size 0 0)
			(layers "F.Cu" "F.Mask" "F.Paste")
			(net "PRSNT_SSD12_FPGA_R_N")
		)
	)
	(footprint ""
		(layer "F.Cu")
		(at 240.300256 -224.319084)
		(property "Reference" "R4526"
			(at 0 0 0)
			(layer "F.SilkS")
			(hide yes)
			(effects
				(font
					(size 1.27 1.27)
				)
			)
		)
		(property "Value" ""
			(at 0 0 0)
			(layer "F.Fab")
			(effects
				(font
					(size 1.27 1.27)
				)
			)
		)
		(duplicate_pad_numbers_are_jumpers no)
		(fp_line
			(start -0.7874 -0.4064)
			(end 0.7874 -0.4064)
			(stroke
				(width 0.1524)
				(type default)
			)
			(layer "F.SilkS")
		)
		(fp_line
			(start -0.7874 0.4064)
			(end -0.7874 -0.4064)
			(stroke
				(width 0.1524)
				(type default)
			)
			(layer "F.SilkS")
		)
		(fp_line
			(start 0.7874 -0.4064)
			(end 0.7874 0.4064)
			(stroke
				(width 0.1524)
				(type default)
			)
			(layer "F.SilkS")
		)
		(fp_line
			(start 0.7874 0.4064)
			(end -0.7874 0.4064)
			(stroke
				(width 0.1524)
				(type default)
			)
			(layer "F.SilkS")
		)
		(fp_line
			(start -0.67945 -0.305054)
			(end -0.12065 -0.305054)
			(stroke
				(width 0.1)
				(type default)
			)
			(layer "F.Fab")
		)
		(fp_line
			(start -0.67945 0.3048)
			(end -0.67945 -0.305054)
			(stroke
				(width 0.1)
				(type default)
			)
			(layer "F.Fab")
		)
		(fp_line
			(start -0.12065 -0.305054)
			(end -0.12065 -0.2794)
			(stroke
				(width 0.1)
				(type default)
			)
			(layer "F.Fab")
		)
		(fp_line
			(start -0.12065 -0.2794)
			(end 0.12065 -0.2794)
			(stroke
				(width 0.1)
				(type default)
			)
			(layer "F.Fab")
		)
		(fp_line
			(start -0.12065 0.2794)
			(end -0.12065 0.3048)
			(stroke
				(width 0.1)
				(type default)
			)
			(layer "F.Fab")
		)
		(fp_line
			(start -0.12065 0.3048)
			(end -0.67945 0.3048)
			(stroke
				(width 0.1)
				(type default)
			)
			(layer "F.Fab")
		)
		(fp_line
			(start 0.120396 0.2794)
			(end -0.12065 0.2794)
			(stroke
				(width 0.1)
				(type default)
			)
			(layer "F.Fab")
		)
		(fp_line
			(start 0.120396 0.3048)
			(end 0.120396 0.2794)
			(stroke
				(width 0.1)
				(type default)
			)
			(layer "F.Fab")
		)
		(fp_line
			(start 0.12065 -0.3048)
			(end 0.67945 -0.3048)
			(stroke
				(width 0.1)
				(type default)
			)
			(layer "F.Fab")
		)
		(fp_line
			(start 0.12065 -0.2794)
			(end 0.12065 -0.3048)
			(stroke
				(width 0.1)
				(type default)
			)
			(layer "F.Fab")
		)
		(fp_line
			(start 0.67945 -0.3048)
			(end 0.67945 0.3048)
			(stroke
				(width 0.1)
				(type default)
			)
			(layer "F.Fab")
		)
		(fp_line
			(start 0.67945 0.3048)
			(end 0.120396 0.3048)
			(stroke
				(width 0.1)
				(type default)
			)
			(layer "F.Fab")
		)
		(pad "1" smd circle
			(at -0.40005 0)
			(size 0 0)
			(layers "F.Cu" "F.Mask" "F.Paste")
			(net "SSD12_PWRDIS_BIC")
		)
		(pad "2" smd circle
			(at 0.40005 0)
			(size 0 0)
			(layers "F.Cu" "F.Mask" "F.Paste")
			(net "SSD12_PWRDIS_BIC_R")
		)
	)
	(footprint ""
		(layer "F.Cu")
		(at 144.526762 -189.758066 180)
		(property "Reference" "C4449"
			(at 0 0 180)
			(layer "F.SilkS")
			(hide yes)
			(effects
				(font
					(size 1.27 1.27)
				)
			)
		)
		(property "Value" ""
			(at 0 0 180)
			(layer "F.Fab")
			(effects
				(font
					(size 1.27 1.27)
				)
			)
		)
		(duplicate_pad_numbers_are_jumpers no)
		(fp_line
			(start 0.7874 0.4064)
			(end -0.7874 0.4064)
			(stroke
				(width 0.1524)
				(type default)
			)
			(layer "F.SilkS")
		)
		(fp_line
			(start 0.7874 -0.4064)
			(end 0.7874 0.4064)
			(stroke
				(width 0.1524)
				(type default)
			)
			(layer "F.SilkS")
		)
		(fp_line
			(start -0.7874 0.4064)
			(end -0.7874 -0.4064)
			(stroke
				(width 0.1524)
				(type default)
			)
			(layer "F.SilkS")
		)
		(fp_line
			(start -0.7874 -0.4064)
			(end 0.7874 -0.4064)
			(stroke
				(width 0.1524)
				(type default)
			)
			(layer "F.SilkS")
		)
		(fp_line
			(start 0.67945 0.3048)
			(end 0.120396 0.3048)
			(stroke
				(width 0.1)
				(type default)
			)
			(layer "F.Fab")
		)
		(fp_line
			(start 0.67945 -0.3048)
			(end 0.67945 0.3048)
			(stroke
				(width 0.1)
				(type default)
			)
			(layer "F.Fab")
		)
		(fp_line
			(start 0.12065 -0.2794)
			(end 0.12065 -0.3048)
			(stroke
				(width 0.1)
				(type default)
			)
			(layer "F.Fab")
		)
		(fp_line
			(start 0.12065 -0.3048)
			(end 0.67945 -0.3048)
			(stroke
				(width 0.1)
				(type default)
			)
			(layer "F.Fab")
		)
		(fp_line
			(start 0.120396 0.3048)
			(end 0.120396 0.2794)
			(stroke
				(width 0.1)
				(type default)
			)
			(layer "F.Fab")
		)
		(fp_line
			(start 0.120396 0.2794)
			(end -0.12065 0.2794)
			(stroke
				(width 0.1)
				(type default)
			)
			(layer "F.Fab")
		)
		(fp_line
			(start -0.12065 0.3048)
			(end -0.67945 0.3048)
			(stroke
				(width 0.1)
				(type default)
			)
			(layer "F.Fab")
		)
		(fp_line
			(start -0.12065 0.2794)
			(end -0.12065 0.3048)
			(stroke
				(width 0.1)
				(type default)
			)
			(layer "F.Fab")
		)
		(fp_line
			(start -0.12065 -0.2794)
			(end 0.12065 -0.2794)
			(stroke
				(width 0.1)
				(type default)
			)
			(layer "F.Fab")
		)
		(fp_line
			(start -0.12065 -0.305054)
			(end -0.12065 -0.2794)
			(stroke
				(width 0.1)
				(type default)
			)
			(layer "F.Fab")
		)
		(fp_line
			(start -0.67945 0.3048)
			(end -0.67945 -0.305054)
			(stroke
				(width 0.1)
				(type default)
			)
			(layer "F.Fab")
		)
		(fp_line
			(start -0.67945 -0.305054)
			(end -0.12065 -0.305054)
			(stroke
				(width 0.1)
				(type default)
			)
			(layer "F.Fab")
		)
		(pad "1" smd circle
			(at -0.40005 0 180)
			(size 0 0)
			(layers "F.Cu" "F.Mask" "F.Paste")
			(net "GND")
		)
		(pad "2" smd circle
			(at 0.40005 0 180)
			(size 0 0)
			(layers "F.Cu" "F.Mask" "F.Paste")
			(net "P3V3_AUX")
		)
	)
)
